# T6G (Grand Teton) — schematic netlist excerpt (pin names and nets, part order shuffled) for the footprints in the layout excerpt that follows; sources: Cadence DE-HDL packaged netlist, KiCad conversion of 04192023_DAF0TMB3IC0_F0TG_MB_C_brd_V02_OCP.brd

PR215  Q_RES  5.6 1% CHIP  pkg 0402LF  page 216 : A = SW_PVDDCR_SOC_P1_BOOT3 ; B = SW_PVDDCR_SOC_P1_BOOT3_RC
R6713  Q_RES  1K 1% EMPTY  pkg 0201LF  page 320 : A = RT_CPU1_P0_ADDR3 ; B = GND
R1148  Q_RES  0 5% CHIP  pkg 0402LF  page 134 : A = HP_LVC3_OCP_V3_1_PRSNT2_N_R ; B = HP_LVC3_OCP_SFF_PRSNT2_PLD_N

(kicad_pcb
	(version 20260206)
	(generator "pcbnew")
	(generator_version "10.0")
	(general
		(thickness 1.6)
		(legacy_teardrops no)
	)
	(paper "A4")
	(title_block
		(title "04192023_DAF0TMB3IC0_F0TG_MB_C_brd_V02_OCP.brd")
		(comment 1 "Grand Teton / footprints 3684-3686 of 8354")
	)
	(layers
		(0 "F.Cu" signal "TOP")
		(4 "In1.Cu" signal "GND")
		(6 "In2.Cu" signal "IN1")
		(8 "In3.Cu" signal "GND1")
		(10 "In4.Cu" signal "IN2")
		(12 "In5.Cu" signal "GND2")
		(14 "In6.Cu" signal "IN3")
		(16 "In7.Cu" signal "GND3")
		(18 "In8.Cu" signal "VCC")
		(20 "In9.Cu" signal "VCC1")
		(22 "In10.Cu" signal "GND4")
		(24 "In11.Cu" signal "IN4")
		(26 "In12.Cu" signal "GND5")
		(28 "In13.Cu" signal "IN5")
		(30 "In14.Cu" signal "GND6")
		(32 "In15.Cu" signal "IN6")
		(34 "In16.Cu" signal "GND7")
		(2 "B.Cu" signal "BOTTOM")
		(9 "F.Adhes" user "F.Adhesive")
		(11 "B.Adhes" user "B.Adhesive")
		(13 "F.Paste" user "Package Geometry/Pastemask Top")
		(15 "B.Paste" user "Package Geometry/Pastemask Bottom")
		(5 "F.SilkS" user "Ref Des/Silkscreen Top")
		(7 "B.SilkS" user "Ref Des/Silkscreen Bottom")
		(1 "F.Mask" user "Board Geometry/Soldermask Top")
		(3 "B.Mask" user "Board Geometry/Soldermask Bottom")
		(17 "Dwgs.User" user "User.Drawings")
		(19 "Cmts.User" user "User.Comments")
		(21 "Eco1.User" user "User.Eco1")
		(23 "Eco2.User" user "User.Eco2")
		(25 "Edge.Cuts" user "Board Geometry/Outline")
		(27 "Margin" user)
		(31 "F.CrtYd" user "Package Geometry/Place Bound Top")
		(29 "B.CrtYd" user "Package Geometry/Place Bound Bottom")
		(35 "F.Fab" user "Ref Des/Assembly Top")
		(33 "B.Fab" user "Ref Des/Assembly Bottom")
	)
	(footprint ""
		(layer "F.Cu")
		(at 461.593946 -108.567728)
		(property "Reference" "R1148"
			(at 0 0 0)
			(layer "F.SilkS")
			(hide yes)
			(effects
				(font
					(size 1.27 1.27)
				)
			)
		)
		(property "Value" ""
			(at 0 0 0)
			(layer "F.Fab")
			(effects
				(font
					(size 1.27 1.27)
				)
			)
		)
		(duplicate_pad_numbers_are_jumpers no)
		(fp_line
			(start -0.7874 -0.4064)
			(end 0.7874 -0.4064)
			(stroke
				(width 0.1524)
				(type default)
			)
			(layer "F.SilkS")
		)
		(fp_line
			(start -0.7874 0.4064)
			(end -0.7874 -0.4064)
			(stroke
				(width 0.1524)
				(type default)
			)
			(layer "F.SilkS")
		)
		(fp_line
			(start 0.7874 -0.4064)
			(end 0.7874 0.4064)
			(stroke
				(width 0.1524)
				(type default)
			)
			(layer "F.SilkS")
		)
		(fp_line
			(start 0.7874 0.4064)
			(end -0.7874 0.4064)
			(stroke
				(width 0.1524)
				(type default)
			)
			(layer "F.SilkS")
		)
		(fp_line
			(start -0.67945 -0.305054)
			(end -0.12065 -0.305054)
			(stroke
				(width 0.1)
				(type default)
			)
			(layer "F.Fab")
		)
		(fp_line
			(start -0.67945 0.3048)
			(end -0.67945 -0.305054)
			(stroke
				(width 0.1)
				(type default)
			)
			(layer "F.Fab")
		)
		(fp_line
			(start -0.12065 -0.305054)
			(end -0.12065 -0.2794)
			(stroke
				(width 0.1)
				(type default)
			)
			(layer "F.Fab")
		)
		(fp_line
			(start -0.12065 -0.2794)
			(end 0.12065 -0.2794)
			(stroke
				(width 0.1)
				(type default)
			)
			(layer "F.Fab")
		)
		(fp_line
			(start -0.12065 0.2794)
			(end -0.12065 0.3048)
			(stroke
				(width 0.1)
				(type default)
			)
			(layer "F.Fab")
		)
		(fp_line
			(start -0.12065 0.3048)
			(end -0.67945 0.3048)
			(stroke
				(width 0.1)
				(type default)
			)
			(layer "F.Fab")
		)
		(fp_line
			(start 0.120396 0.2794)
			(end -0.12065 0.2794)
			(stroke
				(width 0.1)
				(type default)
			)
			(layer "F.Fab")
		)
		(fp_line
			(start 0.120396 0.3048)
			(end 0.120396 0.2794)
			(stroke
				(width 0.1)
				(type default)
			)
			(layer "F.Fab")
		)
		(fp_line
			(start 0.12065 -0.3048)
			(end 0.67945 -0.3048)
			(stroke
				(width 0.1)
				(type default)
			)
			(layer "F.Fab")
		)
		(fp_line
			(start 0.12065 -0.2794)
			(end 0.12065 -0.3048)
			(stroke
				(width 0.1)
				(type default)
			)
			(layer "F.Fab")
		)
		(fp_line
			(start 0.67945 -0.3048)
			(end 0.67945 0.3048)
			(stroke
				(width 0.1)
				(type default)
			)
			(layer "F.Fab")
		)
		(fp_line
			(start 0.67945 0.3048)
			(end 0.120396 0.3048)
			(stroke
				(width 0.1)
				(type default)
			)
			(layer "F.Fab")
		)
		(pad "1" smd circle
			(at -0.40005 0)
			(size 0 0)
			(layers "F.Cu" "F.Mask" "F.Paste")
			(net "HP_LVC3_OCP_V3_1_PRSNT2_N_R")
		)
		(pad "2" smd circle
			(at 0.40005 0)
			(size 0 0)
			(layers "F.Cu" "F.Mask" "F.Paste")
			(net "HP_LVC3_OCP_SFF_PRSNT2_PLD_N")
		)
	)
	(footprint ""
		(layer "F.Cu")
		(at 131.664964 -151.8793 -90)
		(property "Reference" "PR215"
			(at 0 0 270)
			(layer "F.SilkS")
			(hide yes)
			(effects
				(font
					(size 1.27 1.27)
				)
			)
		)
		(property "Value" ""
			(at 0 0 270)
			(layer "F.Fab")
			(effects
				(font
					(size 1.27 1.27)
				)
			)
		)
		(duplicate_pad_numbers_are_jumpers no)
		(fp_line
			(start -0.7874 0.4064)
			(end -0.7874 -0.4064)
			(stroke
				(width 0.1524)
				(type default)
			)
			(layer "F.SilkS")
		)
		(fp_line
			(start 0.7874 0.4064)
			(end -0.7874 0.4064)
			(stroke
				(width 0.1524)
				(type default)
			)
			(layer "F.SilkS")
		)
		(fp_line
			(start -0.7874 -0.4064)
			(end 0.7874 -0.4064)
			(stroke
				(width 0.1524)
				(type default)
			)
			(layer "F.SilkS")
		)
		(fp_line
			(start 0.7874 -0.4064)
			(end 0.7874 0.4064)
			(stroke
				(width 0.1524)
				(type default)
			)
			(layer "F.SilkS")
		)
		(fp_line
			(start -0.67945 0.3048)
			(end -0.67945 -0.305054)
			(stroke
				(width 0.1)
				(type default)
			)
			(layer "F.Fab")
		)
		(fp_line
			(start -0.12065 0.3048)
			(end -0.67945 0.3048)
			(stroke
				(width 0.1)
				(type default)
			)
			(layer "F.Fab")
		)
		(fp_line
			(start 0.120396 0.3048)
			(end 0.120396 0.2794)
			(stroke
				(width 0.1)
				(type default)
			)
			(layer "F.Fab")
		)
		(fp_line
			(start 0.67945 0.3048)
			(end 0.120396 0.3048)
			(stroke
				(width 0.1)
				(type default)
			)
			(layer "F.Fab")
		)
		(fp_line
			(start -0.12065 0.2794)
			(end -0.12065 0.3048)
			(stroke
				(width 0.1)
				(type default)
			)
			(layer "F.Fab")
		)
		(fp_line
			(start 0.120396 0.2794)
			(end -0.12065 0.2794)
			(stroke
				(width 0.1)
				(type default)
			)
			(layer "F.Fab")
		)
		(fp_line
			(start -0.12065 -0.2794)
			(end 0.12065 -0.2794)
			(stroke
				(width 0.1)
				(type default)
			)
			(layer "F.Fab")
		)
		(fp_line
			(start 0.12065 -0.2794)
			(end 0.12065 -0.3048)
			(stroke
				(width 0.1)
				(type default)
			)
			(layer "F.Fab")
		)
		(fp_line
			(start 0.12065 -0.3048)
			(end 0.67945 -0.3048)
			(stroke
				(width 0.1)
				(type default)
			)
			(layer "F.Fab")
		)
		(fp_line
			(start 0.67945 -0.3048)
			(end 0.67945 0.3048)
			(stroke
				(width 0.1)
				(type default)
			)
			(layer "F.Fab")
		)
		(fp_line
			(start -0.67945 -0.305054)
			(end -0.12065 -0.305054)
			(stroke
				(width 0.1)
				(type default)
			)
			(layer "F.Fab")
		)
		(fp_line
			(start -0.12065 -0.305054)
			(end -0.12065 -0.2794)
			(stroke
				(width 0.1)
				(type default)
			)
			(layer "F.Fab")
		)
		(pad "1" smd circle
			(at -0.40005 0 270)
			(size 0 0)
			(layers "F.Cu" "F.Mask" "F.Paste")
			(net "SW_PVDDCR_SOC_P1_BOOT3")
		)
		(pad "2" smd circle
			(at 0.40005 0 270)
			(size 0 0)
			(layers "F.Cu" "F.Mask" "F.Paste")
			(net "SW_PVDDCR_SOC_P1_BOOT3_RC")
		)
	)
	(footprint ""
		(layer "F.Cu")
		(at 71.882 -386.7912 90)
		(property "Reference" "R6713"
			(at 0 0 90)
			(layer "F.SilkS")
			(hide yes)
			(effects
				(font
					(size 1.27 1.27)
				)
			)
		)
		(property "Value" ""
			(at 0 0 90)
			(layer "F.Fab")
			(effects
				(font
					(size 1.27 1.27)
				)
			)
		)
		(duplicate_pad_numbers_are_jumpers no)
		(fp_line
			(start 0.32512 -0.175006)
			(end 0.32512 0.175006)
			(stroke
				(width 0.1)
				(type default)
			)
			(layer "F.Fab")
		)
		(fp_line
			(start -0.32512 -0.175006)
			(end 0.32512 -0.175006)
			(stroke
				(width 0.1)
				(type default)
			)
			(layer "F.Fab")
		)
		(fp_line
			(start 0.32512 0.175006)
			(end -0.32512 0.175006)
			(stroke
				(width 0.1)
				(type default)
			)
			(layer "F.Fab")
		)
		(fp_line
			(start -0.32512 0.175006)
			(end -0.32512 -0.175006)
			(stroke
				(width 0.1)
				(type default)
			)
			(layer "F.Fab")
		)
		(pad "1" smd rect
			(at -0.2667 0 90)
			(size 0.3048 0.381)
			(layers "F.Cu" "F.Mask" "F.Paste")
			(net "RT_CPU1_P0_ADDR3")
		)
		(pad "2" smd rect
			(at 0.2667 0 270)
			(size 0.3048 0.381)
			(layers "F.Cu" "F.Mask" "F.Paste")
			(net "GND")
		)
	)
)
